(kicad_pcb
	(version 20260206)
	(generator "pcbnew")
	(generator_version "10.0")
	(general
		(thickness 1.6)
		(legacy_teardrops no)
	)
	(paper "A4")
	(title_block
		(title "Bryce Canyon_R.DPB_16317-1_OCP.brd")
		(comment 1 "Bryce Canyon / footprints 498-500 of 2099")
	)
	(layers
		(0 "F.Cu" signal "TOP")
		(4 "In1.Cu" signal "L2GND")
		(6 "In2.Cu" signal "L3")
		(8 "In3.Cu" signal "L4VCC")
		(10 "In4.Cu" signal "L5VCC")
		(12 "In5.Cu" signal "L6")
		(14 "In6.Cu" signal "L7GND")
		(2 "B.Cu" signal "BOTTOM")
		(9 "F.Adhes" user "F.Adhesive")
		(11 "B.Adhes" user "B.Adhesive")
		(13 "F.Paste" user "Package Geometry/Pastemask Top")
		(15 "B.Paste" user "Package Geometry/Pastemask Bottom")
		(5 "F.SilkS" user "Ref Des/Silkscreen Top")
		(7 "B.SilkS" user "Ref Des/Silkscreen Bottom")
		(1 "F.Mask" user "Board Geometry/Soldermask Top")
		(3 "B.Mask" user "Board Geometry/Soldermask Bottom")
		(17 "Dwgs.User" user "User.Drawings")
		(19 "Cmts.User" user "User.Comments")
		(21 "Eco1.User" user "User.Eco1")
		(23 "Eco2.User" user "User.Eco2")
		(25 "Edge.Cuts" user "Board Geometry/Outline")
		(27 "Margin" user)
		(31 "F.CrtYd" user "Package Geometry/Place Bound Top")
		(29 "B.CrtYd" user "Package Geometry/Place Bound Bottom")
		(35 "F.Fab" user "Ref Des/Assembly Top")
		(33 "B.Fab" user "Ref Des/Assembly Bottom")
	)
	(footprint ""
		(layer "F.Cu")
		(at 431.546 -131.826 180)
		(property "Reference" "R567"
			(at 0 0 180)
			(layer "F.SilkS")
			(hide yes)
			(effects
				(font
					(size 1.27 1.27)
				)
			)
		)
		(property "Value" "4K7R2J-2-GP"
			(at 0.064008 -3.993896 180)
			(unlocked yes)
			(layer "F.Fab")
			(hide yes)
			(effects
				(font
					(size 1.016 1.016)
					(thickness 0.1524)
				)
			)
		)
		(property "Device Type" "R402H16"
			(at 0.064008 -5.517896 180)
			(unlocked yes)
			(layer "F.Fab")
			(hide yes)
			(effects
				(font
					(size 1.016 1.016)
					(thickness 0.1524)
				)
			)
		)
		(duplicate_pad_numbers_are_jumpers no)
		(fp_line
			(start 0.508 -0.9398)
			(end -0.508 -0.9398)
			(stroke
				(width 0.1524)
				(type default)
			)
			(layer "F.SilkS")
		)
		(fp_line
			(start -0.508 -0.9398)
			(end -0.508 0.9398)
			(stroke
				(width 0.1524)
				(type default)
			)
			(layer "F.SilkS")
		)
		(fp_rect
			(start -0.508 0.9398)
			(end 0.508 -0.9398)
			(stroke
				(width 0)
				(type default)
			)
			(fill no)
			(layer "F.CrtYd")
		)
		(fp_rect
			(start -0.508 0.9398)
			(end 0.508 -0.9398)
			(stroke
				(width 0)
				(type default)
			)
			(fill no)
			(layer "F.Fab")
		)
		(pad "1" smd custom
			(at 0 -0.4445 180)
			(size 0.1397 0.1397)
			(layers "F.Cu" "F.Mask" "F.Paste")
			(net "P12V_B")
			(options
				(clearance outline)
				(anchor circle)
			)
			(primitives
				(gr_poly
					(pts
						(arc
							(start -0.1778 -0.2794)
							(mid -0.249642 -0.249642)
							(end -0.2794 -0.1778)
						)
						(arc
							(start -0.2794 0.1778)
							(mid -0.249642 0.249642)
							(end -0.1778 0.2794)
						)
						(arc
							(start 0.1778 0.2794)
							(mid 0.249642 0.249642)
							(end 0.2794 0.1778)
						)
						(arc
							(start 0.2794 -0.1778)
							(mid 0.249642 -0.249642)
							(end 0.1778 -0.2794)
						)
					)
					(width 0)
					(fill yes)
				)
			)
		)
		(pad "2" smd custom
			(at 0 0.4445 180)
			(size 0.1397 0.1397)
			(layers "F.Cu" "F.Mask" "F.Paste")
			(net "SW_HDD_R21")
			(options
				(clearance outline)
				(anchor circle)
			)
			(primitives
				(gr_poly
					(pts
						(arc
							(start -0.1778 -0.2794)
							(mid -0.249642 -0.249642)
							(end -0.2794 -0.1778)
						)
						(arc
							(start -0.2794 0.1778)
							(mid -0.249642 0.249642)
							(end -0.1778 0.2794)
						)
						(arc
							(start 0.1778 0.2794)
							(mid 0.249642 0.249642)
							(end 0.2794 0.1778)
						)
						(arc
							(start 0.2794 -0.1778)
							(mid 0.249642 -0.249642)
							(end 0.1778 -0.2794)
						)
					)
					(width 0)
					(fill yes)
				)
			)
		)
	)
	(footprint ""
		(layer "F.Cu")
		(at 172.593 -255.524 90)
		(property "Reference" "C104"
			(at 0 0 90)
			(layer "F.SilkS")
			(hide yes)
			(effects
				(font
					(size 1.27 1.27)
				)
			)
		)
		(property "Value" "SCD033U25V2KX-GP"
			(at 1.1811 -2.7051 90)
			(unlocked yes)
			(layer "F.Fab")
			(hide yes)
			(effects
				(font
					(size 1.016 1.016)
					(thickness 0.1524)
				)
			)
		)
		(property "Device Type" "C402H22"
			(at 1.1811 -4.2291 90)
			(unlocked yes)
			(layer "F.Fab")
			(hide yes)
			(effects
				(font
					(size 1.016 1.016)
					(thickness 0.1524)
				)
			)
		)
		(duplicate_pad_numbers_are_jumpers no)
		(fp_rect
			(start -0.4318 0.9525)
			(end 0.4318 -0.9525)
			(stroke
				(width 0)
				(type default)
			)
			(fill no)
			(layer "F.CrtYd")
		)
		(fp_rect
			(start -0.4318 0.9525)
			(end 0.4318 -0.9525)
			(stroke
				(width 0)
				(type default)
			)
			(fill no)
			(layer "F.Fab")
		)
		(pad "1" smd custom
			(at 0 -0.4445 90)
			(size 0.1524 0.1524)
			(layers "F.Cu" "F.Mask" "F.Paste")
			(net "P12V_B")
			(options
				(clearance outline)
				(anchor circle)
			)
			(primitives
				(gr_poly
					(pts
						(arc
							(start 0.3048 -0.2032)
							(mid 0.275042 -0.275042)
							(end 0.2032 -0.3048)
						)
						(arc
							(start -0.2032 -0.3048)
							(mid -0.275042 -0.275042)
							(end -0.3048 -0.2032)
						)
						(arc
							(start -0.3048 0.2032)
							(mid -0.275042 0.275042)
							(end -0.2032 0.3048)
						)
						(arc
							(start 0.2032 0.3048)
							(mid 0.275042 0.275042)
							(end 0.3048 0.2032)
						)
					)
					(width 0)
					(fill yes)
				)
			)
		)
		(pad "2" smd custom
			(at 0 0.4445 90)
			(size 0.1524 0.1524)
			(layers "F.Cu" "F.Mask" "F.Paste")
			(net "SW_HDD_N5")
			(options
				(clearance outline)
				(anchor circle)
			)
			(primitives
				(gr_poly
					(pts
						(arc
							(start 0.3048 -0.2032)
							(mid 0.275042 -0.275042)
							(end 0.2032 -0.3048)
						)
						(arc
							(start -0.2032 -0.3048)
							(mid -0.275042 -0.275042)
							(end -0.3048 -0.2032)
						)
						(arc
							(start -0.3048 0.2032)
							(mid -0.275042 0.275042)
							(end -0.2032 0.3048)
						)
						(arc
							(start 0.2032 0.3048)
							(mid 0.275042 0.275042)
							(end 0.3048 0.2032)
						)
					)
					(width 0)
					(fill yes)
				)
			)
		)
	)
	(footprint ""
		(layer "F.Cu")
		(at 122.849894 -258.910074 -90)
		(property "Reference" "HDDSAS3"
			(at 0 0 270)
			(layer "F.SilkS")
			(hide yes)
			(effects
				(font
					(size 1.27 1.27)
				)
			)
		)
		(property "Value" "SKT-SAS15P-14P-45-GP"
			(at -20.7645 -8.9789 270)
			(unlocked yes)
			(layer "F.Fab")
			(hide yes)
			(effects
				(font
					(size 1.016 1.016)
					(thickness 0.1524)
				)
			)
		)
		(property "Device Type" "10120818-001C-TRLF"
			(at -20.7645 -10.5029 270)
			(unlocked yes)
			(layer "F.Fab")
			(hide yes)
			(effects
				(font
					(size 1.016 1.016)
					(thickness 0.1524)
				)
			)
		)
		(duplicate_pad_numbers_are_jumpers no)
		(fp_line
			(start 1.651 4.2926)
			(end 1.651 3.0099)
			(stroke
				(width 0.1524)
				(type default)
			)
			(layer "F.SilkS")
		)
		(fp_line
			(start 8.509 4.2926)
			(end 1.651 4.2926)
			(stroke
				(width 0.1524)
				(type default)
			)
			(layer "F.SilkS")
		)
		(fp_line
			(start -23.4188 3.0099)
			(end -23.4188 -3.2512)
			(stroke
				(width 0.1524)
				(type default)
			)
			(layer "F.SilkS")
		)
		(fp_line
			(start 1.651 3.0099)
			(end -23.4188 3.0099)
			(stroke
				(width 0.1524)
				(type default)
			)
			(layer "F.SilkS")
		)
		(fp_line
			(start 8.509 3.0099)
			(end 8.509 4.2926)
			(stroke
				(width 0.1524)
				(type default)
			)
			(layer "F.SilkS")
		)
		(fp_line
			(start 23.4188 3.0099)
			(end 8.509 3.0099)
			(stroke
				(width 0.1524)
				(type default)
			)
			(layer "F.SilkS")
		)
		(fp_line
			(start -23.4188 -3.2512)
			(end 23.4188 -3.2512)
			(stroke
				(width 0.1524)
				(type default)
			)
			(layer "F.SilkS")
		)
		(fp_line
			(start 23.4188 -3.2512)
			(end 23.4188 3.0099)
			(stroke
				(width 0.1524)
				(type default)
			)
			(layer "F.SilkS")
		)
		(fp_line
			(start 15.5067 -3.3401)
			(end 16.2687 -3.3401)
			(stroke
				(width 0.3302)
				(type default)
			)
			(layer "F.SilkS")
		)
		(fp_poly
			(pts
				(xy 15.868904 -3.230372) (xy 16.503904 -3.865372) (xy 15.233904 -3.865372)
			)
			(stroke
				(width 0)
				(type default)
			)
			(fill yes)
			(layer "F.SilkS")
		)
		(fp_poly
			(pts
				(xy -22.8727 -2.7559) (xy 22.8727 -2.7559) (xy 22.8727 2.7559) (xy 8.255 2.7559) (xy 8.255 3.5179)
				(xy 1.905 3.5179) (xy 1.905 2.7559) (xy -22.8727 2.7559)
			)
			(stroke
				(width 0)
				(type default)
			)
			(fill no)
			(layer "F.CrtYd")
		)
		(fp_poly
			(pts
				(xy 1.397 4.5466) (xy 1.397 3.2639) (xy -23.6728 3.2639) (xy -23.6728 -3.5052) (xy 23.6728 -3.5052)
				(xy 23.6728 -0.00635) (xy 22.8727 -0.00635) (xy 22.8727 -2.7559) (xy -22.8727 -2.7559) (xy -22.8727 2.7559)
				(xy 1.905 2.7559) (xy 1.905 3.5179) (xy 8.255 3.5179) (xy 8.255 2.7559) (xy 22.8727 2.7559) (xy 22.8727 0.00635)
				(xy 23.6728 0.00635) (xy 23.6728 3.2639) (xy 8.763 3.2639) (xy 8.763 4.5466)
			)
			(stroke
				(width 0)
				(type default)
			)
			(fill no)
			(layer "F.CrtYd")
		)
		(fp_poly
			(pts
				(xy 1.397 4.5466) (xy 1.397 3.2639) (xy -23.6728 3.2639) (xy -23.6728 -3.5052) (xy 23.6728 -3.5052)
				(xy 23.6728 3.2639) (xy 8.763 3.2639) (xy 8.763 4.5466)
			)
			(stroke
				(width 0)
				(type default)
			)
			(fill no)
			(layer "F.Fab")
		)
		(pad "" np_thru_hole circle
			(at -18.874994 0 270)
			(size 0.254 0.254)
			(drill 1.3462)
			(layers "*.Cu" "*.Mask")
			(clearance 0.9017)
			(thermal_gap 0.9017)
		)
		(pad "" np_thru_hole circle
			(at 18.874994 0 270)
			(size 0.254 0.254)
			(drill 0.9398)
			(layers "*.Cu" "*.Mask")
			(clearance 0.6985)
			(thermal_gap 0.6985)
		)
		(pad "G1" smd rect
			(at 21.874988 0 270)
			(size 2.5908 2.5908)
			(layers "F.Cu" "F.Mask" "F.Paste")
			(net "GND")
		)
		(pad "G2" smd rect
			(at -21.874988 0 270)
			(size 2.5908 2.5908)
			(layers "F.Cu" "F.Mask" "F.Paste")
			(net "GND")
		)
		(pad "P1" smd rect
			(at 1.905 -1.82499 270)
			(size 0.6096 2.3622)
			(layers "F.Cu" "F.Mask" "F.Paste")
			(net "Net_1614")
		)
		(pad "P2" smd rect
			(at 0.635 -1.82499 270)
			(size 0.6096 2.3622)
			(layers "F.Cu" "F.Mask" "F.Paste")
			(net "Net_1615")
		)
		(pad "P3" smd rect
			(at -0.635 -1.82499 270)
			(size 0.6096 2.3622)
			(layers "F.Cu" "F.Mask" "F.Paste")
			(net "Net_1616")
		)
		(pad "P4" smd rect
			(at -1.905 -1.82499 270)
			(size 0.6096 2.3622)
			(layers "F.Cu" "F.Mask" "F.Paste")
			(net "GND")
		)
		(pad "P5" smd rect
			(at -3.175 -1.82499 270)
			(size 0.6096 2.3622)
			(layers "F.Cu" "F.Mask" "F.Paste")
			(net "HDD_PRSNT_3")
		)
		(pad "P6" smd rect
			(at -4.445 -1.82499 270)
			(size 0.6096 2.3622)
			(layers "F.Cu" "F.Mask" "F.Paste")
			(net "GND")
		)
		(pad "P7" smd rect
			(at -5.715 -1.82499 270)
			(size 0.6096 2.3622)
			(layers "F.Cu" "F.Mask" "F.Paste")
			(net "5V_PRE_3")
		)
		(pad "P8" smd rect
			(at -6.985 -1.82499 270)
			(size 0.6096 2.3622)
			(layers "F.Cu" "F.Mask" "F.Paste")
			(net "P5V_HDD3")
		)
		(pad "P9" smd rect
			(at -8.255 -1.82499 270)
			(size 0.6096 2.3622)
			(layers "F.Cu" "F.Mask" "F.Paste")
			(net "P5V_HDD3")
		)
		(pad "P10" smd rect
			(at -9.525 -1.82499 270)
			(size 0.6096 2.3622)
			(layers "F.Cu" "F.Mask" "F.Paste")
			(net "GND")
		)
		(pad "P11" smd rect
			(at -10.795 -1.82499 270)
			(size 0.6096 2.3622)
			(layers "F.Cu" "F.Mask" "F.Paste")
			(net "ACT_HDD_3")
		)
		(pad "P12" smd rect
			(at -12.065 -1.82499 270)
			(size 0.6096 2.3622)
			(layers "F.Cu" "F.Mask" "F.Paste")
			(net "GND")
		)
		(pad "P13" smd rect
			(at -13.335 -1.82499 270)
			(size 0.6096 2.3622)
			(layers "F.Cu" "F.Mask" "F.Paste")
			(net "12V_PRE_3")
		)
		(pad "P14" smd rect
			(at -14.605 -1.82499 270)
			(size 0.6096 2.3622)
			(layers "F.Cu" "F.Mask" "F.Paste")
			(net "P12V_HDD3")
		)
		(pad "P15" smd rect
			(at -15.875 -1.82499 270)
			(size 0.6096 2.3622)
			(layers "F.Cu" "F.Mask" "F.Paste")
			(net "P12V_HDD3")
		)
		(pad "S1" smd rect
			(at 15.875 -1.82499 270)
			(size 0.6096 2.3622)
			(layers "F.Cu" "F.Mask" "F.Paste")
			(net "GND")
		)
		(pad "S2" smd rect
			(at 14.605 -1.82499 270)
			(size 0.6096 2.3622)
			(layers "F.Cu" "F.Mask" "F.Paste")
			(net "SAS_HDD_RX_P3")
		)
		(pad "S3" smd rect
			(at 13.335 -1.82499 270)
			(size 0.6096 2.3622)
			(layers "F.Cu" "F.Mask" "F.Paste")
			(net "SAS_HDD_RX_N3")
		)
		(pad "S4" smd rect
			(at 12.065 -1.82499 270)
			(size 0.6096 2.3622)
			(layers "F.Cu" "F.Mask" "F.Paste")
			(net "GND")
		)
		(pad "S5" smd rect
			(at 10.795 -1.82499 270)
			(size 0.6096 2.3622)
			(layers "F.Cu" "F.Mask" "F.Paste")
			(net "PHY_DRV_B_TO_SCC_B_3_DN")
		)
		(pad "S6" smd rect
			(at 9.525 -1.82499 270)
			(size 0.6096 2.3622)
			(layers "F.Cu" "F.Mask" "F.Paste")
			(net "PHY_DRV_B_TO_SCC_B_3_DP")
		)
		(pad "S7" smd rect
			(at 8.255 -1.82499 270)
			(size 0.6096 2.3622)
			(layers "F.Cu" "F.Mask" "F.Paste")
			(net "GND")
		)
		(pad "S8" smd rect
			(at 7.480046 2.845054 270)
			(size 0.508 2.3622)
			(layers "F.Cu" "F.Mask" "F.Paste")
			(net "GND")
		)
		(pad "S9" smd rect
			(at 6.679946 2.845054 270)
			(size 0.508 2.3622)
			(layers "F.Cu" "F.Mask" "F.Paste")
			(net "Net_461")
		)
		(pad "S10" smd rect
			(at 5.8801 2.845054 270)
			(size 0.508 2.3622)
			(layers "F.Cu" "F.Mask" "F.Paste")
			(net "Net_353")
		)
		(pad "S11" smd rect
			(at 5.08 2.845054 270)
			(size 0.508 2.3622)
			(layers "F.Cu" "F.Mask" "F.Paste")
			(net "GND")
		)
		(pad "S12" smd rect
			(at 4.2799 2.845054 270)
			(size 0.508 2.3622)
			(layers "F.Cu" "F.Mask" "F.Paste")
			(net "Net_389")
		)
		(pad "S13" smd rect
			(at 3.480054 2.845054 270)
			(size 0.508 2.3622)
			(layers "F.Cu" "F.Mask" "F.Paste")
			(net "Net_425")
		)
		(pad "S14" smd rect
			(at 2.679954 2.845054 270)
			(size 0.508 2.3622)
			(layers "F.Cu" "F.Mask" "F.Paste")
			(net "GND")
		)
		(zone
			(layer "F.Cu")
			(hatch none 0.5)
			(connect_pads
				(clearance 0)
			)
			(min_thickness 0.25)
			(keepout
				(tracks not_allowed)
				(vias allowed)
				(pads allowed)
				(copperpour not_allowed)
				(footprints allowed)
			)
			(placement
				(enabled no)
				(sheetname "")
			)
			(fill
				(thermal_gap 0.5)
				(thermal_bridge_width 0.5)
				(island_removal_mode 0)
			)
			(polygon
				(pts
					(xy 126.507494 -275.648674) (xy 119.433594 -275.648674) (xy 119.433594 -282.582874) (xy 120.538494 -282.582874)
					(xy 120.538494 -278.468074) (xy 125.161294 -278.468074) (xy 125.161294 -282.582874) (xy 126.507494 -282.582874)
				)
			)
		)
		(zone
			(layer "F.Cu")
			(hatch none 0.5)
			(connect_pads
				(clearance 0)
			)
			(min_thickness 0.25)
			(keepout
				(tracks allowed)
				(vias not_allowed)
				(pads allowed)
				(copperpour not_allowed)
				(footprints allowed)
			)
			(placement
				(enabled no)
				(sheetname "")
			)
			(fill
				(thermal_gap 0.5)
				(thermal_bridge_width 0.5)
				(island_removal_mode 0)
			)
			(polygon
				(pts
					(xy 126.507494 -275.648674) (xy 119.433594 -275.648674) (xy 119.433594 -282.582874) (xy 120.538494 -282.582874)
					(xy 120.538494 -278.468074) (xy 125.161294 -278.468074) (xy 125.161294 -282.582874) (xy 126.507494 -282.582874)
				)
			)
		)
		(zone
			(layer "F.Cu")
			(hatch none 0.5)
			(connect_pads
				(clearance 0)
			)
			(min_thickness 0.25)
			(keepout
				(tracks not_allowed)
				(vias allowed)
				(pads allowed)
				(copperpour not_allowed)
				(footprints allowed)
			)
			(placement
				(enabled no)
				(sheetname "")
			)
			(fill
				(thermal_gap 0.5)
				(thermal_bridge_width 0.5)
				(island_removal_mode 0)
			)
			(polygon
				(pts
					(xy 126.507494 -242.171474) (xy 119.433594 -242.171474) (xy 119.433594 -235.237274) (xy 120.538494 -235.237274)
					(xy 120.538494 -239.352074) (xy 125.161294 -239.352074) (xy 125.161294 -235.237274) (xy 126.507494 -235.237274)
				)
			)
		)
		(zone
			(layer "F.Cu")
			(hatch none 0.5)
			(connect_pads
				(clearance 0)
			)
			(min_thickness 0.25)
			(keepout
				(tracks allowed)
				(vias not_allowed)
				(pads allowed)
				(copperpour not_allowed)
				(footprints allowed)
			)
			(placement
				(enabled no)
				(sheetname "")
			)
			(fill
				(thermal_gap 0.5)
				(thermal_bridge_width 0.5)
				(island_removal_mode 0)
			)
			(polygon
				(pts
					(xy 126.507494 -242.171474) (xy 119.433594 -242.171474) (xy 119.433594 -235.237274) (xy 120.538494 -235.237274)
					(xy 120.538494 -239.352074) (xy 125.161294 -239.352074) (xy 125.161294 -235.237274) (xy 126.507494 -235.237274)
				)
			)
		)
		(zone
			(layers "F.Cu" "B.Cu" "In1.Cu" "In2.Cu" "In3.Cu" "In4.Cu" "In5.Cu" "In6.Cu")
			(hatch none 0.5)
			(connect_pads
				(clearance 0)
			)
			(min_thickness 0.25)
			(keepout
				(tracks not_allowed)
				(vias allowed)
				(pads allowed)
				(copperpour not_allowed)
				(footprints allowed)
			)
			(placement
				(enabled no)
				(sheetname "")
			)
			(fill
				(thermal_gap 0.5)
				(thermal_bridge_width 0.5)
				(island_removal_mode 0)
			)
			(polygon
				(pts
					(arc
						(start 123.624594 -240.03508)
						(mid 122.075194 -240.03508)
						(end 123.624594 -240.03508)
					)
				)
			)
		)
		(zone
			(layers "F.Cu" "B.Cu" "In1.Cu" "In2.Cu" "In3.Cu" "In4.Cu" "In5.Cu" "In6.Cu")
			(hatch none 0.5)
			(connect_pads
				(clearance 0)
			)
			(min_thickness 0.25)
			(keepout
				(tracks not_allowed)
				(vias allowed)
				(pads allowed)
				(copperpour not_allowed)
				(footprints allowed)
			)
			(placement
				(enabled no)
				(sheetname "")
			)
			(fill
				(thermal_gap 0.5)
				(thermal_bridge_width 0.5)
				(island_removal_mode 0)
			)
			(polygon
				(pts
					(arc
						(start 123.827794 -277.785068)
						(mid 121.871994 -277.785068)
						(end 123.827794 -277.785068)
					)
				)
			)
		)
	)
)
